(kicad_pcb
	(version 20260206)
	(generator "pcbnew")
	(generator_version "10.0")
	(general
		(thickness 1.6)
		(legacy_teardrops no)
	)
	(paper "A4")
	(title_block
		(title "04192023_DAF0TMB3IC0_F0TG_MB_C_brd_V02_OCP.brd")
		(comment 1 "Grand Teton / footprints 6274-6280 of 8354")
	)
	(layers
		(0 "F.Cu" signal "TOP")
		(4 "In1.Cu" signal "GND")
		(6 "In2.Cu" signal "IN1")
		(8 "In3.Cu" signal "GND1")
		(10 "In4.Cu" signal "IN2")
		(12 "In5.Cu" signal "GND2")
		(14 "In6.Cu" signal "IN3")
		(16 "In7.Cu" signal "GND3")
		(18 "In8.Cu" signal "VCC")
		(20 "In9.Cu" signal "VCC1")
		(22 "In10.Cu" signal "GND4")
		(24 "In11.Cu" signal "IN4")
		(26 "In12.Cu" signal "GND5")
		(28 "In13.Cu" signal "IN5")
		(30 "In14.Cu" signal "GND6")
		(32 "In15.Cu" signal "IN6")
		(34 "In16.Cu" signal "GND7")
		(2 "B.Cu" signal "BOTTOM")
		(9 "F.Adhes" user "F.Adhesive")
		(11 "B.Adhes" user "B.Adhesive")
		(13 "F.Paste" user "Package Geometry/Pastemask Top")
		(15 "B.Paste" user "Package Geometry/Pastemask Bottom")
		(5 "F.SilkS" user "Ref Des/Silkscreen Top")
		(7 "B.SilkS" user "Ref Des/Silkscreen Bottom")
		(1 "F.Mask" user "Board Geometry/Soldermask Top")
		(3 "B.Mask" user "Board Geometry/Soldermask Bottom")
		(17 "Dwgs.User" user "User.Drawings")
		(19 "Cmts.User" user "User.Comments")
		(21 "Eco1.User" user "User.Eco1")
		(23 "Eco2.User" user "User.Eco2")
		(25 "Edge.Cuts" user "Board Geometry/Outline")
		(27 "Margin" user)
		(31 "F.CrtYd" user "Package Geometry/Place Bound Top")
		(29 "B.CrtYd" user "Package Geometry/Place Bound Bottom")
		(35 "F.Fab" user "Ref Des/Assembly Top")
		(33 "B.Fab" user "Ref Des/Assembly Bottom")
	)
	(footprint ""
		(layer "B.Cu")
		(at 420.160958 -342.007952 -90)
		(property "Reference" "PC221_2"
			(at 0 0 90)
			(layer "B.SilkS")
			(hide yes)
			(effects
				(font
					(size 1.27 1.27)
				)
				(justify mirror)
			)
		)
		(property "Value" ""
			(at 0 0 90)
			(layer "B.Fab")
			(effects
				(font
					(size 1.27 1.27)
				)
				(justify mirror)
			)
		)
		(duplicate_pad_numbers_are_jumpers no)
		(fp_line
			(start -1.524 0.762)
			(end 1.524 0.762)
			(stroke
				(width 0.1524)
				(type default)
			)
			(layer "B.SilkS")
		)
		(fp_line
			(start 1.524 0.762)
			(end 1.524 -0.762)
			(stroke
				(width 0.1524)
				(type default)
			)
			(layer "B.SilkS")
		)
		(fp_line
			(start -1.524 -0.762)
			(end -1.524 0.762)
			(stroke
				(width 0.1524)
				(type default)
			)
			(layer "B.SilkS")
		)
		(fp_line
			(start 1.524 -0.762)
			(end -1.524 -0.762)
			(stroke
				(width 0.1524)
				(type default)
			)
			(layer "B.SilkS")
		)
		(fp_line
			(start -1.1049 0.724916)
			(end -1.1049 -0.724916)
			(stroke
				(width 0.1)
				(type default)
			)
			(layer "B.Fab")
		)
		(fp_line
			(start 1.1049 0.724916)
			(end -1.1049 0.724916)
			(stroke
				(width 0.1)
				(type default)
			)
			(layer "B.Fab")
		)
		(fp_line
			(start -1.1049 -0.724916)
			(end 1.1049 -0.724916)
			(stroke
				(width 0.1)
				(type default)
			)
			(layer "B.Fab")
		)
		(fp_line
			(start 1.1049 -0.724916)
			(end 1.1049 0.724916)
			(stroke
				(width 0.1)
				(type default)
			)
			(layer "B.Fab")
		)
		(pad "1" smd rect
			(at 0.889 0 270)
			(size 1.016 1.27)
			(layers "B.Cu" "B.Mask" "B.Paste")
			(net "PVDD11_S3_P0")
		)
		(pad "2" smd rect
			(at -0.889 0 270)
			(size 1.016 1.27)
			(layers "B.Cu" "B.Mask" "B.Paste")
			(net "GND")
		)
	)
	(footprint ""
		(layer "B.Cu")
		(at 353.900232 -260.305042 180)
		(property "Reference" "C2613"
			(at 0 0 0)
			(layer "B.SilkS")
			(hide yes)
			(effects
				(font
					(size 1.27 1.27)
				)
				(justify mirror)
			)
		)
		(property "Value" ""
			(at 0 0 0)
			(layer "B.Fab")
			(effects
				(font
					(size 1.27 1.27)
				)
				(justify mirror)
			)
		)
		(duplicate_pad_numbers_are_jumpers no)
		(fp_line
			(start 0.7874 0.4064)
			(end 0.7874 -0.4064)
			(stroke
				(width 0.1524)
				(type default)
			)
			(layer "B.SilkS")
		)
		(fp_line
			(start 0.7874 -0.4064)
			(end -0.7874 -0.4064)
			(stroke
				(width 0.1524)
				(type default)
			)
			(layer "B.SilkS")
		)
		(fp_line
			(start -0.7874 0.4064)
			(end 0.7874 0.4064)
			(stroke
				(width 0.1524)
				(type default)
			)
			(layer "B.SilkS")
		)
		(fp_line
			(start -0.7874 -0.4064)
			(end -0.7874 0.4064)
			(stroke
				(width 0.1524)
				(type default)
			)
			(layer "B.SilkS")
		)
		(fp_line
			(start 0.67945 0.3048)
			(end 0.67945 -0.305054)
			(stroke
				(width 0.1)
				(type default)
			)
			(layer "B.Fab")
		)
		(fp_line
			(start 0.67945 -0.305054)
			(end 0.12065 -0.305054)
			(stroke
				(width 0.1)
				(type default)
			)
			(layer "B.Fab")
		)
		(fp_line
			(start 0.12065 0.3048)
			(end 0.67945 0.3048)
			(stroke
				(width 0.1)
				(type default)
			)
			(layer "B.Fab")
		)
		(fp_line
			(start 0.12065 0.2794)
			(end 0.12065 0.3048)
			(stroke
				(width 0.1)
				(type default)
			)
			(layer "B.Fab")
		)
		(fp_line
			(start 0.12065 -0.2794)
			(end -0.12065 -0.2794)
			(stroke
				(width 0.1)
				(type default)
			)
			(layer "B.Fab")
		)
		(fp_line
			(start 0.12065 -0.305054)
			(end 0.12065 -0.2794)
			(stroke
				(width 0.1)
				(type default)
			)
			(layer "B.Fab")
		)
		(fp_line
			(start -0.120396 0.3048)
			(end -0.120396 0.2794)
			(stroke
				(width 0.1)
				(type default)
			)
			(layer "B.Fab")
		)
		(fp_line
			(start -0.120396 0.2794)
			(end 0.12065 0.2794)
			(stroke
				(width 0.1)
				(type default)
			)
			(layer "B.Fab")
		)
		(fp_line
			(start -0.12065 -0.2794)
			(end -0.12065 -0.3048)
			(stroke
				(width 0.1)
				(type default)
			)
			(layer "B.Fab")
		)
		(fp_line
			(start -0.12065 -0.3048)
			(end -0.67945 -0.3048)
			(stroke
				(width 0.1)
				(type default)
			)
			(layer "B.Fab")
		)
		(fp_line
			(start -0.67945 0.3048)
			(end -0.120396 0.3048)
			(stroke
				(width 0.1)
				(type default)
			)
			(layer "B.Fab")
		)
		(fp_line
			(start -0.67945 -0.3048)
			(end -0.67945 0.3048)
			(stroke
				(width 0.1)
				(type default)
			)
			(layer "B.Fab")
		)
		(pad "1" smd circle
			(at 0.40005 0)
			(size 0 0)
			(layers "B.Cu" "B.Mask" "B.Paste")
			(net "PVDDIO_P0")
		)
		(pad "2" smd circle
			(at -0.40005 0)
			(size 0 0)
			(layers "B.Cu" "B.Mask" "B.Paste")
			(net "GND")
		)
	)
	(footprint ""
		(layer "B.Cu")
		(at 104.307894 -333.125826 -90)
		(property "Reference" "PC106"
			(at 7.440676 -3.261106 270)
			(unlocked yes)
			(layer "B.SilkS")
			(effects
				(font
					(size 0.7874 0.5842)
					(thickness 0.1524)
				)
				(justify left mirror)
			)
		)
		(property "Value" ""
			(at 0 0 90)
			(layer "B.Fab")
			(effects
				(font
					(size 1.27 1.27)
				)
				(justify mirror)
			)
		)
		(duplicate_pad_numbers_are_jumpers no)
		(fp_line
			(start -4.533392 2.249932)
			(end 4.533392 2.249932)
			(stroke
				(width 0.1524)
				(type default)
			)
			(layer "B.SilkS")
		)
		(fp_line
			(start 4.533392 2.249932)
			(end 4.533392 -2.249932)
			(stroke
				(width 0.1524)
				(type default)
			)
			(layer "B.SilkS")
		)
		(fp_line
			(start -4.533392 -2.249932)
			(end -4.533392 2.249932)
			(stroke
				(width 0.1524)
				(type default)
			)
			(layer "B.SilkS")
		)
		(fp_line
			(start 4.533392 -2.249932)
			(end -4.533392 -2.249932)
			(stroke
				(width 0.1524)
				(type default)
			)
			(layer "B.SilkS")
		)
		(fp_rect
			(start 5.39242 2.326132)
			(end 4.533392 -2.326132)
			(stroke
				(width 0)
				(type default)
			)
			(fill yes)
			(layer "B.SilkS")
		)
		(fp_line
			(start -3.750056 2.249932)
			(end 3.750056 2.249932)
			(stroke
				(width 0.1)
				(type default)
			)
			(layer "B.Fab")
		)
		(fp_line
			(start 3.750056 2.249932)
			(end 3.750056 -2.249932)
			(stroke
				(width 0.1)
				(type default)
			)
			(layer "B.Fab")
		)
		(fp_line
			(start -3.750056 -2.249932)
			(end -3.750056 2.249932)
			(stroke
				(width 0.1)
				(type default)
			)
			(layer "B.Fab")
		)
		(fp_line
			(start 3.750056 -2.249932)
			(end -3.750056 -2.249932)
			(stroke
				(width 0.1)
				(type default)
			)
			(layer "B.Fab")
		)
		(fp_text user "-"
			(at -4.65201 2.95656 270)
			(unlocked yes)
			(layer "B.SilkS")
			(effects
				(font
					(size 1.905 1.4224)
					(thickness 0.1524)
				)
				(justify left mirror)
			)
		)
		(fp_text user "+"
			(at 6.322314 0.786384 180)
			(unlocked yes)
			(layer "B.SilkS")
			(effects
				(font
					(size 1.905 1.4224)
					(thickness 0.1524)
				)
				(justify left mirror)
			)
		)
		(fp_text user "+"
			(at 6.322314 0.786384 180)
			(unlocked yes)
			(layer "B.Fab")
			(effects
				(font
					(size 1.905 1.4224)
					(thickness 0.1524)
				)
				(justify left mirror)
			)
		)
		(fp_text user "-"
			(at -4.8514 -0.14605 270)
			(unlocked yes)
			(layer "B.Fab")
			(effects
				(font
					(size 1.905 1.4224)
					(thickness 0.1524)
				)
				(justify left mirror)
			)
		)
		(pad "1" smd rect
			(at 3.199892 0 90)
			(size 2.413 2.8194)
			(layers "B.Cu" "B.Mask" "B.Paste")
			(net "PVDDCR_CPU1_P1")
		)
		(pad "2" smd rect
			(at -3.199892 0 90)
			(size 2.413 2.8194)
			(layers "B.Cu" "B.Mask" "B.Paste")
			(net "GND")
		)
	)
	(footprint ""
		(layer "B.Cu")
		(at 130.104642 -74.43724)
		(property "Reference" "PC6018"
			(at 0 0 0)
			(layer "B.SilkS")
			(hide yes)
			(effects
				(font
					(size 1.27 1.27)
				)
				(justify mirror)
			)
		)
		(property "Value" ""
			(at 0 0 0)
			(layer "B.Fab")
			(effects
				(font
					(size 1.27 1.27)
				)
				(justify mirror)
			)
		)
		(duplicate_pad_numbers_are_jumpers no)
		(fp_line
			(start -1.524 -0.762)
			(end -1.524 0.762)
			(stroke
				(width 0.1524)
				(type default)
			)
			(layer "B.SilkS")
		)
		(fp_line
			(start -1.524 0.762)
			(end 1.524 0.762)
			(stroke
				(width 0.1524)
				(type default)
			)
			(layer "B.SilkS")
		)
		(fp_line
			(start 1.524 -0.762)
			(end -1.524 -0.762)
			(stroke
				(width 0.1524)
				(type default)
			)
			(layer "B.SilkS")
		)
		(fp_line
			(start 1.524 0.762)
			(end 1.524 -0.762)
			(stroke
				(width 0.1524)
				(type default)
			)
			(layer "B.SilkS")
		)
		(fp_line
			(start -1.1049 -0.724916)
			(end 1.1049 -0.724916)
			(stroke
				(width 0.1)
				(type default)
			)
			(layer "B.Fab")
		)
		(fp_line
			(start -1.1049 0.724916)
			(end -1.1049 -0.724916)
			(stroke
				(width 0.1)
				(type default)
			)
			(layer "B.Fab")
		)
		(fp_line
			(start 1.1049 -0.724916)
			(end 1.1049 0.724916)
			(stroke
				(width 0.1)
				(type default)
			)
			(layer "B.Fab")
		)
		(fp_line
			(start 1.1049 0.724916)
			(end -1.1049 0.724916)
			(stroke
				(width 0.1)
				(type default)
			)
			(layer "B.Fab")
		)
		(pad "1" smd rect
			(at 0.889 0)
			(size 1.016 1.27)
			(layers "B.Cu" "B.Mask" "B.Paste")
			(net "P1V2_AUX")
		)
		(pad "2" smd rect
			(at -0.889 0)
			(size 1.016 1.27)
			(layers "B.Cu" "B.Mask" "B.Paste")
			(net "GND")
		)
	)
	(footprint ""
		(layer "B.Cu")
		(at 92.281502 -205.14945 90)
		(property "Reference" "R537"
			(at 0 0 90)
			(layer "B.SilkS")
			(hide yes)
			(effects
				(font
					(size 1.27 1.27)
				)
				(justify mirror)
			)
		)
		(property "Value" ""
			(at 0 0 90)
			(layer "B.Fab")
			(effects
				(font
					(size 1.27 1.27)
				)
				(justify mirror)
			)
		)
		(duplicate_pad_numbers_are_jumpers no)
		(fp_line
			(start 0.7874 -0.4064)
			(end -0.7874 -0.4064)
			(stroke
				(width 0.1524)
				(type default)
			)
			(layer "B.SilkS")
		)
		(fp_line
			(start -0.7874 -0.4064)
			(end -0.7874 0.4064)
			(stroke
				(width 0.1524)
				(type default)
			)
			(layer "B.SilkS")
		)
		(fp_line
			(start 0.7874 0.4064)
			(end 0.7874 -0.4064)
			(stroke
				(width 0.1524)
				(type default)
			)
			(layer "B.SilkS")
		)
		(fp_line
			(start -0.7874 0.4064)
			(end 0.7874 0.4064)
			(stroke
				(width 0.1524)
				(type default)
			)
			(layer "B.SilkS")
		)
		(fp_line
			(start 0.67945 -0.305054)
			(end 0.12065 -0.305054)
			(stroke
				(width 0.1)
				(type default)
			)
			(layer "B.Fab")
		)
		(fp_line
			(start 0.12065 -0.305054)
			(end 0.12065 -0.2794)
			(stroke
				(width 0.1)
				(type default)
			)
			(layer "B.Fab")
		)
		(fp_line
			(start -0.12065 -0.3048)
			(end -0.67945 -0.3048)
			(stroke
				(width 0.1)
				(type default)
			)
			(layer "B.Fab")
		)
		(fp_line
			(start -0.67945 -0.3048)
			(end -0.67945 0.3048)
			(stroke
				(width 0.1)
				(type default)
			)
			(layer "B.Fab")
		)
		(fp_line
			(start 0.12065 -0.2794)
			(end -0.12065 -0.2794)
			(stroke
				(width 0.1)
				(type default)
			)
			(layer "B.Fab")
		)
		(fp_line
			(start -0.12065 -0.2794)
			(end -0.12065 -0.3048)
			(stroke
				(width 0.1)
				(type default)
			)
			(layer "B.Fab")
		)
		(fp_line
			(start 0.12065 0.2794)
			(end 0.12065 0.3048)
			(stroke
				(width 0.1)
				(type default)
			)
			(layer "B.Fab")
		)
		(fp_line
			(start -0.120396 0.2794)
			(end 0.12065 0.2794)
			(stroke
				(width 0.1)
				(type default)
			)
			(layer "B.Fab")
		)
		(fp_line
			(start 0.67945 0.3048)
			(end 0.67945 -0.305054)
			(stroke
				(width 0.1)
				(type default)
			)
			(layer "B.Fab")
		)
		(fp_line
			(start 0.12065 0.3048)
			(end 0.67945 0.3048)
			(stroke
				(width 0.1)
				(type default)
			)
			(layer "B.Fab")
		)
		(fp_line
			(start -0.120396 0.3048)
			(end -0.120396 0.2794)
			(stroke
				(width 0.1)
				(type default)
			)
			(layer "B.Fab")
		)
		(fp_line
			(start -0.67945 0.3048)
			(end -0.120396 0.3048)
			(stroke
				(width 0.1)
				(type default)
			)
			(layer "B.Fab")
		)
		(pad "1" smd circle
			(at 0.40005 0 270)
			(size 0 0)
			(layers "B.Cu" "B.Mask" "B.Paste")
			(net "CPU1_XTRIG_L4")
		)
		(pad "2" smd circle
			(at -0.40005 0 270)
			(size 0 0)
			(layers "B.Cu" "B.Mask" "B.Paste")
			(net "PVDD18_S5_P1")
		)
	)
	(footprint ""
		(layer "B.Cu")
		(at 58.213244 -349.386398 -90)
		(property "Reference" "PR268"
			(at 0 0 90)
			(layer "B.SilkS")
			(hide yes)
			(effects
				(font
					(size 1.27 1.27)
				)
				(justify mirror)
			)
		)
		(property "Value" ""
			(at 0 0 90)
			(layer "B.Fab")
			(effects
				(font
					(size 1.27 1.27)
				)
				(justify mirror)
			)
		)
		(duplicate_pad_numbers_are_jumpers no)
		(fp_line
			(start -0.7874 0.4064)
			(end 0.7874 0.4064)
			(stroke
				(width 0.1524)
				(type default)
			)
			(layer "B.SilkS")
		)
		(fp_line
			(start 0.7874 0.4064)
			(end 0.7874 -0.4064)
			(stroke
				(width 0.1524)
				(type default)
			)
			(layer "B.SilkS")
		)
		(fp_line
			(start -0.7874 -0.4064)
			(end -0.7874 0.4064)
			(stroke
				(width 0.1524)
				(type default)
			)
			(layer "B.SilkS")
		)
		(fp_line
			(start 0.7874 -0.4064)
			(end -0.7874 -0.4064)
			(stroke
				(width 0.1524)
				(type default)
			)
			(layer "B.SilkS")
		)
		(fp_line
			(start -0.67945 0.3048)
			(end -0.120396 0.3048)
			(stroke
				(width 0.1)
				(type default)
			)
			(layer "B.Fab")
		)
		(fp_line
			(start -0.120396 0.3048)
			(end -0.120396 0.2794)
			(stroke
				(width 0.1)
				(type default)
			)
			(layer "B.Fab")
		)
		(fp_line
			(start 0.12065 0.3048)
			(end 0.67945 0.3048)
			(stroke
				(width 0.1)
				(type default)
			)
			(layer "B.Fab")
		)
		(fp_line
			(start 0.67945 0.3048)
			(end 0.67945 -0.305054)
			(stroke
				(width 0.1)
				(type default)
			)
			(layer "B.Fab")
		)
		(fp_line
			(start -0.120396 0.2794)
			(end 0.12065 0.2794)
			(stroke
				(width 0.1)
				(type default)
			)
			(layer "B.Fab")
		)
		(fp_line
			(start 0.12065 0.2794)
			(end 0.12065 0.3048)
			(stroke
				(width 0.1)
				(type default)
			)
			(layer "B.Fab")
		)
		(fp_line
			(start -0.12065 -0.2794)
			(end -0.12065 -0.3048)
			(stroke
				(width 0.1)
				(type default)
			)
			(layer "B.Fab")
		)
		(fp_line
			(start 0.12065 -0.2794)
			(end -0.12065 -0.2794)
			(stroke
				(width 0.1)
				(type default)
			)
			(layer "B.Fab")
		)
		(fp_line
			(start -0.67945 -0.3048)
			(end -0.67945 0.3048)
			(stroke
				(width 0.1)
				(type default)
			)
			(layer "B.Fab")
		)
		(fp_line
			(start -0.12065 -0.3048)
			(end -0.67945 -0.3048)
			(stroke
				(width 0.1)
				(type default)
			)
			(layer "B.Fab")
		)
		(fp_line
			(start 0.12065 -0.305054)
			(end 0.12065 -0.2794)
			(stroke
				(width 0.1)
				(type default)
			)
			(layer "B.Fab")
		)
		(fp_line
			(start 0.67945 -0.305054)
			(end 0.12065 -0.305054)
			(stroke
				(width 0.1)
				(type default)
			)
			(layer "B.Fab")
		)
		(pad "1" smd circle
			(at 0.40005 0 90)
			(size 0 0)
			(layers "B.Cu" "B.Mask" "B.Paste")
			(net "PVDDCR_CPU1_P1_VOS4")
		)
		(pad "2" smd circle
			(at -0.40005 0 90)
			(size 0 0)
			(layers "B.Cu" "B.Mask" "B.Paste")
			(net "PVDDCR_CPU1_P1")
		)
	)
	(footprint ""
		(layer "B.Cu")
		(at 200.952608 -120.737376)
		(property "Reference" "R648"
			(at 0 0 0)
			(layer "B.SilkS")
			(hide yes)
			(effects
				(font
					(size 1.27 1.27)
				)
				(justify mirror)
			)
		)
		(property "Value" ""
			(at 0 0 0)
			(layer "B.Fab")
			(effects
				(font
					(size 1.27 1.27)
				)
				(justify mirror)
			)
		)
		(duplicate_pad_numbers_are_jumpers no)
		(fp_line
			(start -0.7874 -0.4064)
			(end -0.7874 0.4064)
			(stroke
				(width 0.1524)
				(type default)
			)
			(layer "B.SilkS")
		)
		(fp_line
			(start -0.7874 0.4064)
			(end 0.7874 0.4064)
			(stroke
				(width 0.1524)
				(type default)
			)
			(layer "B.SilkS")
		)
		(fp_line
			(start 0.7874 -0.4064)
			(end -0.7874 -0.4064)
			(stroke
				(width 0.1524)
				(type default)
			)
			(layer "B.SilkS")
		)
		(fp_line
			(start 0.7874 0.4064)
			(end 0.7874 -0.4064)
			(stroke
				(width 0.1524)
				(type default)
			)
			(layer "B.SilkS")
		)
		(fp_line
			(start -0.67945 -0.3048)
			(end -0.67945 0.3048)
			(stroke
				(width 0.1)
				(type default)
			)
			(layer "B.Fab")
		)
		(fp_line
			(start -0.67945 0.3048)
			(end -0.120396 0.3048)
			(stroke
				(width 0.1)
				(type default)
			)
			(layer "B.Fab")
		)
		(fp_line
			(start -0.12065 -0.3048)
			(end -0.67945 -0.3048)
			(stroke
				(width 0.1)
				(type default)
			)
			(layer "B.Fab")
		)
		(fp_line
			(start -0.12065 -0.2794)
			(end -0.12065 -0.3048)
			(stroke
				(width 0.1)
				(type default)
			)
			(layer "B.Fab")
		)
		(fp_line
			(start -0.120396 0.2794)
			(end 0.12065 0.2794)
			(stroke
				(width 0.1)
				(type default)
			)
			(layer "B.Fab")
		)
		(fp_line
			(start -0.120396 0.3048)
			(end -0.120396 0.2794)
			(stroke
				(width 0.1)
				(type default)
			)
			(layer "B.Fab")
		)
		(fp_line
			(start 0.12065 -0.305054)
			(end 0.12065 -0.2794)
			(stroke
				(width 0.1)
				(type default)
			)
			(layer "B.Fab")
		)
		(fp_line
			(start 0.12065 -0.2794)
			(end -0.12065 -0.2794)
			(stroke
				(width 0.1)
				(type default)
			)
			(layer "B.Fab")
		)
		(fp_line
			(start 0.12065 0.2794)
			(end 0.12065 0.3048)
			(stroke
				(width 0.1)
				(type default)
			)
			(layer "B.Fab")
		)
		(fp_line
			(start 0.12065 0.3048)
			(end 0.67945 0.3048)
			(stroke
				(width 0.1)
				(type default)
			)
			(layer "B.Fab")
		)
		(fp_line
			(start 0.67945 -0.305054)
			(end 0.12065 -0.305054)
			(stroke
				(width 0.1)
				(type default)
			)
			(layer "B.Fab")
		)
		(fp_line
			(start 0.67945 0.3048)
			(end 0.67945 -0.305054)
			(stroke
				(width 0.1)
				(type default)
			)
			(layer "B.Fab")
		)
		(pad "1" smd circle
			(at 0.40005 0 180)
			(size 0 0)
			(layers "B.Cu" "B.Mask" "B.Paste")
			(net "E1S_0_P3V3_EN")
		)
		(pad "2" smd circle
			(at -0.40005 0 180)
			(size 0 0)
			(layers "B.Cu" "B.Mask" "B.Paste")
			(net "P3V3_E1S_0_EN_R")
		)
	)
)
